# T6G (Grand Teton) — schematic netlist excerpt (pin names and nets, part order shuffled) for the footprints in the layout excerpt that follows; sources: Cadence DE-HDL packaged netlist, KiCad conversion of 04192023_DAF0TMB3IC0_F0TG_MB_C_brd_V02_OCP.brd

PC265_2  Q_CAP  22UF 16V 20% X6S  pkg C0805  page 211 : A = SW_P12V_AUX_PVDDCR_CPU0_P1_FLT ; B = GND
R262  Q_RES  0 5% CHIP  pkg 0402LF  page 82 : A = CPU1_CORETYPE0 ; B = FM_CPU1_CORETYPE0

(kicad_pcb
	(version 20260206)
	(generator "pcbnew")
	(generator_version "10.0")
	(general
		(thickness 1.6)
		(legacy_teardrops no)
	)
	(paper "A4")
	(title_block
		(title "04192023_DAF0TMB3IC0_F0TG_MB_C_brd_V02_OCP.brd")
		(comment 1 "Grand Teton / footprints 6945-6946 of 8354")
	)
	(layers
		(0 "F.Cu" signal "TOP")
		(4 "In1.Cu" signal "GND")
		(6 "In2.Cu" signal "IN1")
		(8 "In3.Cu" signal "GND1")
		(10 "In4.Cu" signal "IN2")
		(12 "In5.Cu" signal "GND2")
		(14 "In6.Cu" signal "IN3")
		(16 "In7.Cu" signal "GND3")
		(18 "In8.Cu" signal "VCC")
		(20 "In9.Cu" signal "VCC1")
		(22 "In10.Cu" signal "GND4")
		(24 "In11.Cu" signal "IN4")
		(26 "In12.Cu" signal "GND5")
		(28 "In13.Cu" signal "IN5")
		(30 "In14.Cu" signal "GND6")
		(32 "In15.Cu" signal "IN6")
		(34 "In16.Cu" signal "GND7")
		(2 "B.Cu" signal "BOTTOM")
		(9 "F.Adhes" user "F.Adhesive")
		(11 "B.Adhes" user "B.Adhesive")
		(13 "F.Paste" user "Package Geometry/Pastemask Top")
		(15 "B.Paste" user "Package Geometry/Pastemask Bottom")
		(5 "F.SilkS" user "Ref Des/Silkscreen Top")
		(7 "B.SilkS" user "Ref Des/Silkscreen Bottom")
		(1 "F.Mask" user "Board Geometry/Soldermask Top")
		(3 "B.Mask" user "Board Geometry/Soldermask Bottom")
		(17 "Dwgs.User" user "User.Drawings")
		(19 "Cmts.User" user "User.Comments")
		(21 "Eco1.User" user "User.Eco1")
		(23 "Eco2.User" user "User.Eco2")
		(25 "Edge.Cuts" user "Board Geometry/Outline")
		(27 "Margin" user)
		(31 "F.CrtYd" user "Package Geometry/Place Bound Top")
		(29 "B.CrtYd" user "Package Geometry/Place Bound Bottom")
		(35 "F.Fab" user "Ref Des/Assembly Top")
		(33 "B.Fab" user "Ref Des/Assembly Bottom")
	)
	(footprint ""
		(layer "B.Cu")
		(at 89.560146 -182.607966 -90)
		(property "Reference" "PC265_2"
			(at 0 0 90)
			(layer "B.SilkS")
			(hide yes)
			(effects
				(font
					(size 1.27 1.27)
				)
				(justify mirror)
			)
		)
		(property "Value" ""
			(at 0 0 90)
			(layer "B.Fab")
			(effects
				(font
					(size 1.27 1.27)
				)
				(justify mirror)
			)
		)
		(duplicate_pad_numbers_are_jumpers no)
		(fp_line
			(start -1.524 0.762)
			(end 1.524 0.762)
			(stroke
				(width 0.1524)
				(type default)
			)
			(layer "B.SilkS")
		)
		(fp_line
			(start 1.524 0.762)
			(end 1.524 -0.762)
			(stroke
				(width 0.1524)
				(type default)
			)
			(layer "B.SilkS")
		)
		(fp_line
			(start -1.524 -0.762)
			(end -1.524 0.762)
			(stroke
				(width 0.1524)
				(type default)
			)
			(layer "B.SilkS")
		)
		(fp_line
			(start 1.524 -0.762)
			(end -1.524 -0.762)
			(stroke
				(width 0.1524)
				(type default)
			)
			(layer "B.SilkS")
		)
		(fp_line
			(start -1.1049 0.724916)
			(end -1.1049 -0.724916)
			(stroke
				(width 0.1)
				(type default)
			)
			(layer "B.Fab")
		)
		(fp_line
			(start 1.1049 0.724916)
			(end -1.1049 0.724916)
			(stroke
				(width 0.1)
				(type default)
			)
			(layer "B.Fab")
		)
		(fp_line
			(start -1.1049 -0.724916)
			(end 1.1049 -0.724916)
			(stroke
				(width 0.1)
				(type default)
			)
			(layer "B.Fab")
		)
		(fp_line
			(start 1.1049 -0.724916)
			(end 1.1049 0.724916)
			(stroke
				(width 0.1)
				(type default)
			)
			(layer "B.Fab")
		)
		(pad "1" smd rect
			(at 0.889 0 270)
			(size 1.016 1.27)
			(layers "B.Cu" "B.Mask" "B.Paste")
			(net "SW_P12V_AUX_PVDDCR_CPU0_P1_FLT")
		)
		(pad "2" smd rect
			(at -0.889 0 270)
			(size 1.016 1.27)
			(layers "B.Cu" "B.Mask" "B.Paste")
			(net "GND")
		)
	)
	(footprint ""
		(layer "B.Cu")
		(at 187.822078 -97.085912 -90)
		(property "Reference" "R262"
			(at 0 0 90)
			(layer "B.SilkS")
			(hide yes)
			(effects
				(font
					(size 1.27 1.27)
				)
				(justify mirror)
			)
		)
		(property "Value" ""
			(at 0 0 90)
			(layer "B.Fab")
			(effects
				(font
					(size 1.27 1.27)
				)
				(justify mirror)
			)
		)
		(duplicate_pad_numbers_are_jumpers no)
		(fp_line
			(start -0.7874 0.4064)
			(end 0.7874 0.4064)
			(stroke
				(width 0.1524)
				(type default)
			)
			(layer "B.SilkS")
		)
		(fp_line
			(start 0.7874 0.4064)
			(end 0.7874 -0.4064)
			(stroke
				(width 0.1524)
				(type default)
			)
			(layer "B.SilkS")
		)
		(fp_line
			(start -0.7874 -0.4064)
			(end -0.7874 0.4064)
			(stroke
				(width 0.1524)
				(type default)
			)
			(layer "B.SilkS")
		)
		(fp_line
			(start 0.7874 -0.4064)
			(end -0.7874 -0.4064)
			(stroke
				(width 0.1524)
				(type default)
			)
			(layer "B.SilkS")
		)
		(fp_line
			(start -0.67945 0.3048)
			(end -0.120396 0.3048)
			(stroke
				(width 0.1)
				(type default)
			)
			(layer "B.Fab")
		)
		(fp_line
			(start -0.120396 0.3048)
			(end -0.120396 0.2794)
			(stroke
				(width 0.1)
				(type default)
			)
			(layer "B.Fab")
		)
		(fp_line
			(start 0.12065 0.3048)
			(end 0.67945 0.3048)
			(stroke
				(width 0.1)
				(type default)
			)
			(layer "B.Fab")
		)
		(fp_line
			(start 0.67945 0.3048)
			(end 0.67945 -0.305054)
			(stroke
				(width 0.1)
				(type default)
			)
			(layer "B.Fab")
		)
		(fp_line
			(start -0.120396 0.2794)
			(end 0.12065 0.2794)
			(stroke
				(width 0.1)
				(type default)
			)
			(layer "B.Fab")
		)
		(fp_line
			(start 0.12065 0.2794)
			(end 0.12065 0.3048)
			(stroke
				(width 0.1)
				(type default)
			)
			(layer "B.Fab")
		)
		(fp_line
			(start -0.12065 -0.2794)
			(end -0.12065 -0.3048)
			(stroke
				(width 0.1)
				(type default)
			)
			(layer "B.Fab")
		)
		(fp_line
			(start 0.12065 -0.2794)
			(end -0.12065 -0.2794)
			(stroke
				(width 0.1)
				(type default)
			)
			(layer "B.Fab")
		)
		(fp_line
			(start -0.67945 -0.3048)
			(end -0.67945 0.3048)
			(stroke
				(width 0.1)
				(type default)
			)
			(layer "B.Fab")
		)
		(fp_line
			(start -0.12065 -0.3048)
			(end -0.67945 -0.3048)
			(stroke
				(width 0.1)
				(type default)
			)
			(layer "B.Fab")
		)
		(fp_line
			(start 0.12065 -0.305054)
			(end 0.12065 -0.2794)
			(stroke
				(width 0.1)
				(type default)
			)
			(layer "B.Fab")
		)
		(fp_line
			(start 0.67945 -0.305054)
			(end 0.12065 -0.305054)
			(stroke
				(width 0.1)
				(type default)
			)
			(layer "B.Fab")
		)
		(pad "1" smd circle
			(at 0.40005 0 90)
			(size 0 0)
			(layers "B.Cu" "B.Mask" "B.Paste")
			(net "CPU1_CORETYPE0")
		)
		(pad "2" smd circle
			(at -0.40005 0 90)
			(size 0 0)
			(layers "B.Cu" "B.Mask" "B.Paste")
			(net "FM_CPU1_CORETYPE0")
		)
	)
)
